(kicad_pcb
	(version 20260206)
	(generator "pcbnew")
	(generator_version "10.0")
	(general
		(thickness 1.6)
		(legacy_teardrops no)
	)
	(paper "A4")
	(title_block
		(title "04192023_DAF0TMB3IC0_F0TG_MB_C_brd_V02_OCP.brd")
		(comment 1 "Grand Teton / footprints 3002-3009 of 8354")
	)
	(layers
		(0 "F.Cu" signal "TOP")
		(4 "In1.Cu" signal "GND")
		(6 "In2.Cu" signal "IN1")
		(8 "In3.Cu" signal "GND1")
		(10 "In4.Cu" signal "IN2")
		(12 "In5.Cu" signal "GND2")
		(14 "In6.Cu" signal "IN3")
		(16 "In7.Cu" signal "GND3")
		(18 "In8.Cu" signal "VCC")
		(20 "In9.Cu" signal "VCC1")
		(22 "In10.Cu" signal "GND4")
		(24 "In11.Cu" signal "IN4")
		(26 "In12.Cu" signal "GND5")
		(28 "In13.Cu" signal "IN5")
		(30 "In14.Cu" signal "GND6")
		(32 "In15.Cu" signal "IN6")
		(34 "In16.Cu" signal "GND7")
		(2 "B.Cu" signal "BOTTOM")
		(9 "F.Adhes" user "F.Adhesive")
		(11 "B.Adhes" user "B.Adhesive")
		(13 "F.Paste" user "Package Geometry/Pastemask Top")
		(15 "B.Paste" user "Package Geometry/Pastemask Bottom")
		(5 "F.SilkS" user "Ref Des/Silkscreen Top")
		(7 "B.SilkS" user "Ref Des/Silkscreen Bottom")
		(1 "F.Mask" user "Board Geometry/Soldermask Top")
		(3 "B.Mask" user "Board Geometry/Soldermask Bottom")
		(17 "Dwgs.User" user "User.Drawings")
		(19 "Cmts.User" user "User.Comments")
		(21 "Eco1.User" user "User.Eco1")
		(23 "Eco2.User" user "User.Eco2")
		(25 "Edge.Cuts" user "Board Geometry/Outline")
		(27 "Margin" user)
		(31 "F.CrtYd" user "Package Geometry/Place Bound Top")
		(29 "B.CrtYd" user "Package Geometry/Place Bound Bottom")
		(35 "F.Fab" user "Ref Des/Assembly Top")
		(33 "B.Fab" user "Ref Des/Assembly Bottom")
	)
	(footprint ""
		(layer "F.Cu")
		(at 26.684478 -16.099536 90)
		(property "Reference" "C686"
			(at 0 0 90)
			(layer "F.SilkS")
			(hide yes)
			(effects
				(font
					(size 1.27 1.27)
				)
			)
		)
		(property "Value" ""
			(at 0 0 90)
			(layer "F.Fab")
			(effects
				(font
					(size 1.27 1.27)
				)
			)
		)
		(duplicate_pad_numbers_are_jumpers no)
		(fp_line
			(start 0.299974 -0.150114)
			(end 0.299974 0.150114)
			(stroke
				(width 0.1)
				(type default)
			)
			(layer "F.Fab")
		)
		(fp_line
			(start -0.299974 -0.150114)
			(end 0.299974 -0.150114)
			(stroke
				(width 0.1)
				(type default)
			)
			(layer "F.Fab")
		)
		(fp_line
			(start 0.299974 0.150114)
			(end -0.299974 0.150114)
			(stroke
				(width 0.1)
				(type default)
			)
			(layer "F.Fab")
		)
		(fp_line
			(start -0.299974 0.150114)
			(end -0.299974 -0.150114)
			(stroke
				(width 0.1)
				(type default)
			)
			(layer "F.Fab")
		)
		(pad "1" smd rect
			(at -0.2667 0 90)
			(size 0.3048 0.381)
			(layers "F.Cu" "F.Mask" "F.Paste")
			(net "P5E_CPU1_G1_TX_C_DN<11>")
		)
		(pad "2" smd rect
			(at 0.2667 0 90)
			(size 0.3048 0.381)
			(layers "F.Cu" "F.Mask" "F.Paste")
			(net "P5E_CPU1_G1_TX_DN<11>")
		)
	)
	(footprint ""
		(layer "F.Cu")
		(at 8.343138 -136.15416 90)
		(property "Reference" "C71"
			(at 0 0 90)
			(layer "F.SilkS")
			(hide yes)
			(effects
				(font
					(size 1.27 1.27)
				)
			)
		)
		(property "Value" ""
			(at 0 0 90)
			(layer "F.Fab")
			(effects
				(font
					(size 1.27 1.27)
				)
			)
		)
		(duplicate_pad_numbers_are_jumpers no)
		(fp_line
			(start 0.7874 -0.4064)
			(end 0.7874 0.4064)
			(stroke
				(width 0.1524)
				(type default)
			)
			(layer "F.SilkS")
		)
		(fp_line
			(start -0.7874 -0.4064)
			(end 0.7874 -0.4064)
			(stroke
				(width 0.1524)
				(type default)
			)
			(layer "F.SilkS")
		)
		(fp_line
			(start 0.7874 0.4064)
			(end -0.7874 0.4064)
			(stroke
				(width 0.1524)
				(type default)
			)
			(layer "F.SilkS")
		)
		(fp_line
			(start -0.7874 0.4064)
			(end -0.7874 -0.4064)
			(stroke
				(width 0.1524)
				(type default)
			)
			(layer "F.SilkS")
		)
		(fp_line
			(start -0.12065 -0.305054)
			(end -0.12065 -0.2794)
			(stroke
				(width 0.1)
				(type default)
			)
			(layer "F.Fab")
		)
		(fp_line
			(start -0.67945 -0.305054)
			(end -0.12065 -0.305054)
			(stroke
				(width 0.1)
				(type default)
			)
			(layer "F.Fab")
		)
		(fp_line
			(start 0.67945 -0.3048)
			(end 0.67945 0.3048)
			(stroke
				(width 0.1)
				(type default)
			)
			(layer "F.Fab")
		)
		(fp_line
			(start 0.12065 -0.3048)
			(end 0.67945 -0.3048)
			(stroke
				(width 0.1)
				(type default)
			)
			(layer "F.Fab")
		)
		(fp_line
			(start 0.12065 -0.2794)
			(end 0.12065 -0.3048)
			(stroke
				(width 0.1)
				(type default)
			)
			(layer "F.Fab")
		)
		(fp_line
			(start -0.12065 -0.2794)
			(end 0.12065 -0.2794)
			(stroke
				(width 0.1)
				(type default)
			)
			(layer "F.Fab")
		)
		(fp_line
			(start 0.120396 0.2794)
			(end -0.12065 0.2794)
			(stroke
				(width 0.1)
				(type default)
			)
			(layer "F.Fab")
		)
		(fp_line
			(start -0.12065 0.2794)
			(end -0.12065 0.3048)
			(stroke
				(width 0.1)
				(type default)
			)
			(layer "F.Fab")
		)
		(fp_line
			(start 0.67945 0.3048)
			(end 0.120396 0.3048)
			(stroke
				(width 0.1)
				(type default)
			)
			(layer "F.Fab")
		)
		(fp_line
			(start 0.120396 0.3048)
			(end 0.120396 0.2794)
			(stroke
				(width 0.1)
				(type default)
			)
			(layer "F.Fab")
		)
		(fp_line
			(start -0.12065 0.3048)
			(end -0.67945 0.3048)
			(stroke
				(width 0.1)
				(type default)
			)
			(layer "F.Fab")
		)
		(fp_line
			(start -0.67945 0.3048)
			(end -0.67945 -0.305054)
			(stroke
				(width 0.1)
				(type default)
			)
			(layer "F.Fab")
		)
		(pad "1" smd circle
			(at -0.40005 0 90)
			(size 0 0)
			(layers "F.Cu" "F.Mask" "F.Paste")
			(net "CLK_GEN2_XTAL_IN_R")
		)
		(pad "2" smd circle
			(at 0.40005 0 90)
			(size 0 0)
			(layers "F.Cu" "F.Mask" "F.Paste")
			(net "GND")
		)
	)
	(footprint ""
		(layer "F.Cu")
		(at 83.589114 -177.532284)
		(property "Reference" "PR187"
			(at 0 0 0)
			(layer "F.SilkS")
			(hide yes)
			(effects
				(font
					(size 1.27 1.27)
				)
			)
		)
		(property "Value" ""
			(at 0 0 0)
			(layer "F.Fab")
			(effects
				(font
					(size 1.27 1.27)
				)
			)
		)
		(duplicate_pad_numbers_are_jumpers no)
		(fp_line
			(start -0.7874 -0.4064)
			(end 0.7874 -0.4064)
			(stroke
				(width 0.1524)
				(type default)
			)
			(layer "F.SilkS")
		)
		(fp_line
			(start -0.7874 0.4064)
			(end -0.7874 -0.4064)
			(stroke
				(width 0.1524)
				(type default)
			)
			(layer "F.SilkS")
		)
		(fp_line
			(start 0.7874 -0.4064)
			(end 0.7874 0.4064)
			(stroke
				(width 0.1524)
				(type default)
			)
			(layer "F.SilkS")
		)
		(fp_line
			(start 0.7874 0.4064)
			(end -0.7874 0.4064)
			(stroke
				(width 0.1524)
				(type default)
			)
			(layer "F.SilkS")
		)
		(fp_line
			(start -0.67945 -0.305054)
			(end -0.12065 -0.305054)
			(stroke
				(width 0.1)
				(type default)
			)
			(layer "F.Fab")
		)
		(fp_line
			(start -0.67945 0.3048)
			(end -0.67945 -0.305054)
			(stroke
				(width 0.1)
				(type default)
			)
			(layer "F.Fab")
		)
		(fp_line
			(start -0.12065 -0.305054)
			(end -0.12065 -0.2794)
			(stroke
				(width 0.1)
				(type default)
			)
			(layer "F.Fab")
		)
		(fp_line
			(start -0.12065 -0.2794)
			(end 0.12065 -0.2794)
			(stroke
				(width 0.1)
				(type default)
			)
			(layer "F.Fab")
		)
		(fp_line
			(start -0.12065 0.2794)
			(end -0.12065 0.3048)
			(stroke
				(width 0.1)
				(type default)
			)
			(layer "F.Fab")
		)
		(fp_line
			(start -0.12065 0.3048)
			(end -0.67945 0.3048)
			(stroke
				(width 0.1)
				(type default)
			)
			(layer "F.Fab")
		)
		(fp_line
			(start 0.120396 0.2794)
			(end -0.12065 0.2794)
			(stroke
				(width 0.1)
				(type default)
			)
			(layer "F.Fab")
		)
		(fp_line
			(start 0.120396 0.3048)
			(end 0.120396 0.2794)
			(stroke
				(width 0.1)
				(type default)
			)
			(layer "F.Fab")
		)
		(fp_line
			(start 0.12065 -0.3048)
			(end 0.67945 -0.3048)
			(stroke
				(width 0.1)
				(type default)
			)
			(layer "F.Fab")
		)
		(fp_line
			(start 0.12065 -0.2794)
			(end 0.12065 -0.3048)
			(stroke
				(width 0.1)
				(type default)
			)
			(layer "F.Fab")
		)
		(fp_line
			(start 0.67945 -0.3048)
			(end 0.67945 0.3048)
			(stroke
				(width 0.1)
				(type default)
			)
			(layer "F.Fab")
		)
		(fp_line
			(start 0.67945 0.3048)
			(end 0.120396 0.3048)
			(stroke
				(width 0.1)
				(type default)
			)
			(layer "F.Fab")
		)
		(pad "1" smd circle
			(at -0.40005 0)
			(size 0 0)
			(layers "F.Cu" "F.Mask" "F.Paste")
			(net "GND")
		)
		(pad "2" smd circle
			(at 0.40005 0)
			(size 0 0)
			(layers "F.Cu" "F.Mask" "F.Paste")
			(net "PVDDCR_CPU0_P1_LSET1")
		)
	)
	(footprint ""
		(layer "F.Cu")
		(at 213.919054 -124.604018)
		(property "Reference" "R905"
			(at 0 0 0)
			(layer "F.SilkS")
			(hide yes)
			(effects
				(font
					(size 1.27 1.27)
				)
			)
		)
		(property "Value" ""
			(at 0 0 0)
			(layer "F.Fab")
			(effects
				(font
					(size 1.27 1.27)
				)
			)
		)
		(duplicate_pad_numbers_are_jumpers no)
		(fp_line
			(start -0.7874 -0.4064)
			(end 0.7874 -0.4064)
			(stroke
				(width 0.1524)
				(type default)
			)
			(layer "F.SilkS")
		)
		(fp_line
			(start -0.7874 0.4064)
			(end -0.7874 -0.4064)
			(stroke
				(width 0.1524)
				(type default)
			)
			(layer "F.SilkS")
		)
		(fp_line
			(start 0.7874 -0.4064)
			(end 0.7874 0.4064)
			(stroke
				(width 0.1524)
				(type default)
			)
			(layer "F.SilkS")
		)
		(fp_line
			(start 0.7874 0.4064)
			(end -0.7874 0.4064)
			(stroke
				(width 0.1524)
				(type default)
			)
			(layer "F.SilkS")
		)
		(fp_line
			(start -0.67945 -0.305054)
			(end -0.12065 -0.305054)
			(stroke
				(width 0.1)
				(type default)
			)
			(layer "F.Fab")
		)
		(fp_line
			(start -0.67945 0.3048)
			(end -0.67945 -0.305054)
			(stroke
				(width 0.1)
				(type default)
			)
			(layer "F.Fab")
		)
		(fp_line
			(start -0.12065 -0.305054)
			(end -0.12065 -0.2794)
			(stroke
				(width 0.1)
				(type default)
			)
			(layer "F.Fab")
		)
		(fp_line
			(start -0.12065 -0.2794)
			(end 0.12065 -0.2794)
			(stroke
				(width 0.1)
				(type default)
			)
			(layer "F.Fab")
		)
		(fp_line
			(start -0.12065 0.2794)
			(end -0.12065 0.3048)
			(stroke
				(width 0.1)
				(type default)
			)
			(layer "F.Fab")
		)
		(fp_line
			(start -0.12065 0.3048)
			(end -0.67945 0.3048)
			(stroke
				(width 0.1)
				(type default)
			)
			(layer "F.Fab")
		)
		(fp_line
			(start 0.120396 0.2794)
			(end -0.12065 0.2794)
			(stroke
				(width 0.1)
				(type default)
			)
			(layer "F.Fab")
		)
		(fp_line
			(start 0.120396 0.3048)
			(end 0.120396 0.2794)
			(stroke
				(width 0.1)
				(type default)
			)
			(layer "F.Fab")
		)
		(fp_line
			(start 0.12065 -0.3048)
			(end 0.67945 -0.3048)
			(stroke
				(width 0.1)
				(type default)
			)
			(layer "F.Fab")
		)
		(fp_line
			(start 0.12065 -0.2794)
			(end 0.12065 -0.3048)
			(stroke
				(width 0.1)
				(type default)
			)
			(layer "F.Fab")
		)
		(fp_line
			(start 0.67945 -0.3048)
			(end 0.67945 0.3048)
			(stroke
				(width 0.1)
				(type default)
			)
			(layer "F.Fab")
		)
		(fp_line
			(start 0.67945 0.3048)
			(end 0.120396 0.3048)
			(stroke
				(width 0.1)
				(type default)
			)
			(layer "F.Fab")
		)
		(pad "1" smd circle
			(at -0.40005 0)
			(size 0 0)
			(layers "F.Cu" "F.Mask" "F.Paste")
			(net "RST_PERST_OCP_SFF_BUF2_N")
		)
		(pad "2" smd circle
			(at 0.40005 0)
			(size 0 0)
			(layers "F.Cu" "F.Mask" "F.Paste")
			(net "RST_PERST2_OCP_SFF_N")
		)
	)
	(footprint ""
		(layer "F.Cu")
		(at 161.731706 -408.517344 -90)
		(property "Reference" "C6723"
			(at 0 0 270)
			(layer "F.SilkS")
			(hide yes)
			(effects
				(font
					(size 1.27 1.27)
				)
			)
		)
		(property "Value" ""
			(at 0 0 270)
			(layer "F.Fab")
			(effects
				(font
					(size 1.27 1.27)
				)
			)
		)
		(duplicate_pad_numbers_are_jumpers no)
		(fp_line
			(start -0.299974 0.150114)
			(end -0.299974 -0.150114)
			(stroke
				(width 0.1)
				(type default)
			)
			(layer "F.Fab")
		)
		(fp_line
			(start 0.299974 0.150114)
			(end -0.299974 0.150114)
			(stroke
				(width 0.1)
				(type default)
			)
			(layer "F.Fab")
		)
		(fp_line
			(start -0.299974 -0.150114)
			(end 0.299974 -0.150114)
			(stroke
				(width 0.1)
				(type default)
			)
			(layer "F.Fab")
		)
		(fp_line
			(start 0.299974 -0.150114)
			(end 0.299974 0.150114)
			(stroke
				(width 0.1)
				(type default)
			)
			(layer "F.Fab")
		)
		(pad "1" smd rect
			(at -0.2667 0 270)
			(size 0.3048 0.381)
			(layers "F.Cu" "F.Mask" "F.Paste")
			(net "P5E_CPU1_P2_TX_BUF_C_DP<15>")
		)
		(pad "2" smd rect
			(at 0.2667 0 270)
			(size 0.3048 0.381)
			(layers "F.Cu" "F.Mask" "F.Paste")
			(net "P5E_CPU1_P2_TX_BUF_DP<15>")
		)
	)
	(footprint ""
		(layer "F.Cu")
		(at 178.943 -133.568948 -90)
		(property "Reference" "R216"
			(at 0 0 270)
			(layer "F.SilkS")
			(hide yes)
			(effects
				(font
					(size 1.27 1.27)
				)
			)
		)
		(property "Value" ""
			(at 0 0 270)
			(layer "F.Fab")
			(effects
				(font
					(size 1.27 1.27)
				)
			)
		)
		(duplicate_pad_numbers_are_jumpers no)
		(fp_line
			(start -0.7874 0.4064)
			(end -0.7874 -0.4064)
			(stroke
				(width 0.1524)
				(type default)
			)
			(layer "F.SilkS")
		)
		(fp_line
			(start 0.7874 0.4064)
			(end -0.7874 0.4064)
			(stroke
				(width 0.1524)
				(type default)
			)
			(layer "F.SilkS")
		)
		(fp_line
			(start -0.7874 -0.4064)
			(end 0.7874 -0.4064)
			(stroke
				(width 0.1524)
				(type default)
			)
			(layer "F.SilkS")
		)
		(fp_line
			(start 0.7874 -0.4064)
			(end 0.7874 0.4064)
			(stroke
				(width 0.1524)
				(type default)
			)
			(layer "F.SilkS")
		)
		(fp_line
			(start -0.67945 0.3048)
			(end -0.67945 -0.305054)
			(stroke
				(width 0.1)
				(type default)
			)
			(layer "F.Fab")
		)
		(fp_line
			(start -0.12065 0.3048)
			(end -0.67945 0.3048)
			(stroke
				(width 0.1)
				(type default)
			)
			(layer "F.Fab")
		)
		(fp_line
			(start 0.120396 0.3048)
			(end 0.120396 0.2794)
			(stroke
				(width 0.1)
				(type default)
			)
			(layer "F.Fab")
		)
		(fp_line
			(start 0.67945 0.3048)
			(end 0.120396 0.3048)
			(stroke
				(width 0.1)
				(type default)
			)
			(layer "F.Fab")
		)
		(fp_line
			(start -0.12065 0.2794)
			(end -0.12065 0.3048)
			(stroke
				(width 0.1)
				(type default)
			)
			(layer "F.Fab")
		)
		(fp_line
			(start 0.120396 0.2794)
			(end -0.12065 0.2794)
			(stroke
				(width 0.1)
				(type default)
			)
			(layer "F.Fab")
		)
		(fp_line
			(start -0.12065 -0.2794)
			(end 0.12065 -0.2794)
			(stroke
				(width 0.1)
				(type default)
			)
			(layer "F.Fab")
		)
		(fp_line
			(start 0.12065 -0.2794)
			(end 0.12065 -0.3048)
			(stroke
				(width 0.1)
				(type default)
			)
			(layer "F.Fab")
		)
		(fp_line
			(start 0.12065 -0.3048)
			(end 0.67945 -0.3048)
			(stroke
				(width 0.1)
				(type default)
			)
			(layer "F.Fab")
		)
		(fp_line
			(start 0.67945 -0.3048)
			(end 0.67945 0.3048)
			(stroke
				(width 0.1)
				(type default)
			)
			(layer "F.Fab")
		)
		(fp_line
			(start -0.67945 -0.305054)
			(end -0.12065 -0.305054)
			(stroke
				(width 0.1)
				(type default)
			)
			(layer "F.Fab")
		)
		(fp_line
			(start -0.12065 -0.305054)
			(end -0.12065 -0.2794)
			(stroke
				(width 0.1)
				(type default)
			)
			(layer "F.Fab")
		)
		(pad "1" smd circle
			(at -0.40005 0 270)
			(size 0 0)
			(layers "F.Cu" "F.Mask" "F.Paste")
			(net "RST_CPU0_SYS_N")
		)
		(pad "2" smd circle
			(at 0.40005 0 270)
			(size 0 0)
			(layers "F.Cu" "F.Mask" "F.Paste")
			(net "FM_CPU0_SYS_RESET_N")
		)
	)
	(footprint ""
		(layer "F.Cu")
		(at 28.021026 -427.612302)
		(property "Reference" "R6157"
			(at 0 0 0)
			(layer "F.SilkS")
			(hide yes)
			(effects
				(font
					(size 1.27 1.27)
				)
			)
		)
		(property "Value" ""
			(at 0 0 0)
			(layer "F.Fab")
			(effects
				(font
					(size 1.27 1.27)
				)
			)
		)
		(duplicate_pad_numbers_are_jumpers no)
		(fp_line
			(start -0.32512 -0.175006)
			(end 0.32512 -0.175006)
			(stroke
				(width 0.1)
				(type default)
			)
			(layer "F.Fab")
		)
		(fp_line
			(start -0.32512 0.175006)
			(end -0.32512 -0.175006)
			(stroke
				(width 0.1)
				(type default)
			)
			(layer "F.Fab")
		)
		(fp_line
			(start 0.32512 -0.175006)
			(end 0.32512 0.175006)
			(stroke
				(width 0.1)
				(type default)
			)
			(layer "F.Fab")
		)
		(fp_line
			(start 0.32512 0.175006)
			(end -0.32512 0.175006)
			(stroke
				(width 0.1)
				(type default)
			)
			(layer "F.Fab")
		)
		(pad "1" smd rect
			(at -0.2667 0)
			(size 0.3048 0.381)
			(layers "F.Cu" "F.Mask" "F.Paste")
			(net "P2E_MB_BMC_RX_DN<0>")
		)
		(pad "2" smd rect
			(at 0.2667 0 180)
			(size 0.3048 0.381)
			(layers "F.Cu" "F.Mask" "F.Paste")
			(net "P2E_MB_BMC_RX_R1_DN<0>")
		)
	)
	(footprint ""
		(layer "F.Cu")
		(at 51.746404 -408.517344 -90)
		(property "Reference" "C6631"
			(at 0 0 270)
			(layer "F.SilkS")
			(hide yes)
			(effects
				(font
					(size 1.27 1.27)
				)
			)
		)
		(property "Value" ""
			(at 0 0 270)
			(layer "F.Fab")
			(effects
				(font
					(size 1.27 1.27)
				)
			)
		)
		(duplicate_pad_numbers_are_jumpers no)
		(fp_line
			(start -0.299974 0.150114)
			(end -0.299974 -0.150114)
			(stroke
				(width 0.1)
				(type default)
			)
			(layer "F.Fab")
		)
		(fp_line
			(start 0.299974 0.150114)
			(end -0.299974 0.150114)
			(stroke
				(width 0.1)
				(type default)
			)
			(layer "F.Fab")
		)
		(fp_line
			(start -0.299974 -0.150114)
			(end 0.299974 -0.150114)
			(stroke
				(width 0.1)
				(type default)
			)
			(layer "F.Fab")
		)
		(fp_line
			(start 0.299974 -0.150114)
			(end 0.299974 0.150114)
			(stroke
				(width 0.1)
				(type default)
			)
			(layer "F.Fab")
		)
		(pad "1" smd rect
			(at -0.2667 0 270)
			(size 0.3048 0.381)
			(layers "F.Cu" "F.Mask" "F.Paste")
			(net "P5E_CPU1_P0_TX_BUF_C_DP<1>")
		)
		(pad "2" smd rect
			(at 0.2667 0 270)
			(size 0.3048 0.381)
			(layers "F.Cu" "F.Mask" "F.Paste")
			(net "P5E_CPU1_P0_TX_BUF_DP<1>")
		)
	)
)
